FILE_TYPE = MACRO_DRAWING;
SET COLOR_WIRE YELLOW;
SET COLOR_PROP MONO;
SET COLOR_DOT WHITE;
SET COLOR_ARC YELLOW;
SET COLOR_BODY GREEN;
SET COLOR_NOTE MONO;
SET PROP_DISPLAY VALUE;
SET PAGE_NUMBER P63;
FORCEADD OFFPAGE..1
(-6300 2250);
FORCEPROP 2 LAST $XR0 113 
J 0
(-6552 2250);
DISPLAY 0.638298 (-6552 2250);
PAINT MONO (-6552 2250);
FORCEPROP 2 LAST $XR1 29 
J 0
(-6642 2250);
DISPLAY 0.638298 (-6642 2250);
PAINT MONO (-6642 2250);
FORCEPROP 2 LAST CDS_LIB mstr_standard
J 0
(-6300 2250);
PAINT ORANGE (-6300 2250);
DISPLAY INVISIBLE (-6300 2250);
FORCEPROP 1 LAST OFFPAGE TRUE
J 0
(-5975 2125);
DISPLAY 0.872340 (-5975 2125);
PAINT GREEN (-5975 2125);
DISPLAY INVISIBLE (-5975 2125);
FORCEPROP 1 LAST COMMENT_BODY TRUE
J 0
(-6175 2150);
DISPLAY 0.872340 (-6175 2150);
PAINT GREEN (-6175 2150);
DISPLAY INVISIBLE (-6175 2150);
FORCEPROP 2 LAST PATH I10
J 0
(-6250 2325);
DISPLAY 1.021277 (-6250 2325);
PAINT ORANGE (-6250 2325);
DISPLAY INVISIBLE (-6250 2325);
FORCEADD OFFPAGE..1
(-6300 2350);
FORCEPROP 2 LAST $XR0 113 
J 0
(-6552 2350);
DISPLAY 0.638298 (-6552 2350);
PAINT MONO (-6552 2350);
FORCEPROP 2 LAST $XR1 29 
J 0
(-6642 2350);
DISPLAY 0.638298 (-6642 2350);
PAINT MONO (-6642 2350);
FORCEPROP 2 LAST CDS_LIB mstr_standard
J 0
(-6300 2350);
PAINT ORANGE (-6300 2350);
DISPLAY INVISIBLE (-6300 2350);
FORCEPROP 1 LAST OFFPAGE TRUE
J 0
(-5975 2225);
DISPLAY 0.872340 (-5975 2225);
PAINT GREEN (-5975 2225);
DISPLAY INVISIBLE (-5975 2225);
FORCEPROP 1 LAST COMMENT_BODY TRUE
J 0
(-6175 2250);
DISPLAY 0.872340 (-6175 2250);
PAINT GREEN (-6175 2250);
DISPLAY INVISIBLE (-6175 2250);
FORCEPROP 2 LAST PATH I12
J 0
(-6550 2400);
DISPLAY 1.021277 (-6550 2400);
PAINT ORANGE (-6550 2400);
DISPLAY INVISIBLE (-6550 2400);
FORCEADD OFFPAGE..1
R 2
(-2150 2900);
FORCEPROP 2 LAST $XR0 103 
J 0
(-1964 2900);
DISPLAY 0.638298 (-1964 2900);
PAINT MONO (-1964 2900);
FORCEPROP 2 LAST CDS_LIB mstr_standard
J 2
(-2150 2900);
PAINT ORANGE (-2150 2900);
DISPLAY INVISIBLE (-2150 2900);
FORCEPROP 1 LAST OFFPAGE TRUE
J 2
(-2475 2775);
DISPLAY 0.872340 (-2475 2775);
PAINT GREEN (-2475 2775);
DISPLAY INVISIBLE (-2475 2775);
FORCEPROP 1 LAST COMMENT_BODY TRUE
J 2
(-2275 2800);
DISPLAY 0.872340 (-2275 2800);
PAINT GREEN (-2275 2800);
DISPLAY INVISIBLE (-2275 2800);
FORCEPROP 2 LAST PATH I15
J 0
(-1975 2975);
DISPLAY 1.021277 (-1975 2975);
PAINT ORANGE (-1975 2975);
DISPLAY INVISIBLE (-1975 2975);
FORCEADD OFFPAGE..1
R 2
(-2150 2850);
FORCEPROP 2 LAST $XR0 103 
J 0
(-1964 2850);
DISPLAY 0.638298 (-1964 2850);
PAINT MONO (-1964 2850);
FORCEPROP 2 LAST CDS_LIB mstr_standard
J 2
(-2150 2850);
PAINT ORANGE (-2150 2850);
DISPLAY INVISIBLE (-2150 2850);
FORCEPROP 1 LAST OFFPAGE TRUE
J 2
(-2475 2725);
DISPLAY 0.872340 (-2475 2725);
PAINT GREEN (-2475 2725);
DISPLAY INVISIBLE (-2475 2725);
FORCEPROP 1 LAST COMMENT_BODY TRUE
J 2
(-2275 2750);
DISPLAY 0.872340 (-2275 2750);
PAINT GREEN (-2275 2750);
DISPLAY INVISIBLE (-2275 2750);
FORCEPROP 2 LAST PATH I16
J 0
(-1975 2925);
DISPLAY 1.021277 (-1975 2925);
PAINT ORANGE (-1975 2925);
DISPLAY INVISIBLE (-1975 2925);
FORCEADD OFFPAGE..1
(-6300 2900);
FORCEPROP 2 LAST $XR0 104 
J 0
(-6552 2900);
DISPLAY 0.638298 (-6552 2900);
PAINT MONO (-6552 2900);
FORCEPROP 2 LAST CDS_LIB mstr_standard
J 0
(-6300 2900);
PAINT ORANGE (-6300 2900);
DISPLAY INVISIBLE (-6300 2900);
FORCEPROP 1 LAST OFFPAGE TRUE
J 0
(-5975 2775);
DISPLAY 0.872340 (-5975 2775);
PAINT GREEN (-5975 2775);
DISPLAY INVISIBLE (-5975 2775);
FORCEPROP 1 LAST COMMENT_BODY TRUE
J 0
(-6175 2800);
DISPLAY 0.872340 (-6175 2800);
PAINT GREEN (-6175 2800);
DISPLAY INVISIBLE (-6175 2800);
FORCEPROP 2 LAST PATH I20
J 0
(-6250 2975);
DISPLAY 1.021277 (-6250 2975);
PAINT ORANGE (-6250 2975);
DISPLAY INVISIBLE (-6250 2975);
FORCEADD OFFPAGE..1
(-6300 2850);
FORCEPROP 2 LAST $XR0 104 
J 0
(-6552 2850);
DISPLAY 0.638298 (-6552 2850);
PAINT MONO (-6552 2850);
FORCEPROP 2 LAST CDS_LIB mstr_standard
J 0
(-6300 2850);
PAINT ORANGE (-6300 2850);
DISPLAY INVISIBLE (-6300 2850);
FORCEPROP 1 LAST OFFPAGE TRUE
J 0
(-5975 2725);
DISPLAY 0.872340 (-5975 2725);
PAINT GREEN (-5975 2725);
DISPLAY INVISIBLE (-5975 2725);
FORCEPROP 1 LAST COMMENT_BODY TRUE
J 0
(-6175 2750);
DISPLAY 0.872340 (-6175 2750);
PAINT GREEN (-6175 2750);
DISPLAY INVISIBLE (-6175 2750);
FORCEPROP 2 LAST PATH I21
J 0
(-6250 2925);
DISPLAY 1.021277 (-6250 2925);
PAINT ORANGE (-6250 2925);
DISPLAY INVISIBLE (-6250 2925);
FORCEADD OFFPAGE..1
R 2
(-2175 2300);
FORCEPROP 2 LAST $XR0 190 
J 0
(-1989 2300);
DISPLAY 0.638298 (-1989 2300);
PAINT MONO (-1989 2300);
FORCEPROP 2 LAST $XR1 192 
J 0
(-1869 2300);
DISPLAY 0.638298 (-1869 2300);
PAINT MONO (-1869 2300);
FORCEPROP 2 LAST CDS_LIB mstr_standard
J 0
(-2175 2300);
PAINT MONO (-2175 2300);
DISPLAY INVISIBLE (-2175 2300);
FORCEPROP 1 LAST OFFPAGE TRUE
J 2
(-2500 2175);
DISPLAY 0.872340 (-2500 2175);
PAINT GREEN (-2500 2175);
DISPLAY INVISIBLE (-2500 2175);
FORCEPROP 1 LAST COMMENT_BODY TRUE
J 2
(-2300 2200);
DISPLAY 0.872340 (-2300 2200);
PAINT GREEN (-2300 2200);
DISPLAY INVISIBLE (-2300 2200);
FORCEPROP 2 LAST PATH I22
J 0
(-2000 2375);
DISPLAY 1.021277 (-2000 2375);
PAINT ORANGE (-2000 2375);
DISPLAY INVISIBLE (-2000 2375);
FORCEADD SKX_EXT_B..9
(-4075 2500);
FORCEPROP 1 LAST LOCATION U2D1
J 0
(-4975 3650);
DISPLAY 0.617021 (-4975 3650);
PAINT AQUA (-4975 3650);
FORCEPROP 1 LAST PART_NUMBER TBD
J 0
(-4975 1350);
DISPLAY 0.617021 (-4975 1350);
PAINT BLUE (-4975 1350);
FORCEPROP 1 LAST MATERIAL IC
J 0
(-4975 3600);
DISPLAY 0.617021 (-4975 3600);
PAINT SKYBLUE (-4975 3600);
FORCEPROP 2 LASTPIN (-3125 2100) $PN AR20
J 0
(-3115 2110);
DISPLAY 0.617021 (-3115 2110);
PAINT ORANGE (-3115 2110);
FORCEPROP 2 LASTPIN (-3125 2050) $PN AR22
J 0
(-3115 2060);
DISPLAY 0.617021 (-3115 2060);
PAINT ORANGE (-3115 2060);
FORCEPROP 2 LASTPIN (-3125 1950) $PN AR26
J 0
(-3115 1960);
DISPLAY 0.617021 (-3115 1960);
PAINT ORANGE (-3115 1960);
FORCEPROP 2 LASTPIN (-3125 1900) $PN AR62
J 0
(-3115 1910);
DISPLAY 0.617021 (-3115 1910);
PAINT ORANGE (-3115 1910);
FORCEPROP 2 LASTPIN (-3125 1850) $PN AT13
J 0
(-3115 1860);
DISPLAY 0.617021 (-3115 1860);
PAINT ORANGE (-3115 1860);
FORCEPROP 2 LASTPIN (-3125 1800) $PN AT23
J 0
(-3115 1810);
DISPLAY 0.617021 (-3115 1810);
PAINT ORANGE (-3115 1810);
FORCEPROP 2 LASTPIN (-3125 1750) $PN AT25
J 0
(-3115 1760);
DISPLAY 0.617021 (-3115 1760);
PAINT ORANGE (-3115 1760);
FORCEPROP 2 LASTPIN (-3125 1700) $PN AV77
J 0
(-3115 1710);
DISPLAY 0.617021 (-3115 1710);
PAINT ORANGE (-3115 1710);
FORCEPROP 2 LASTPIN (-3125 1650) $PN AW64
J 0
(-3115 1660);
DISPLAY 0.617021 (-3115 1660);
PAINT ORANGE (-3115 1660);
FORCEPROP 2 LASTPIN (-5025 2100) $PN AW76
J 2
(-5035 2110);
DISPLAY 0.617021 (-5035 2110);
PAINT ORANGE (-5035 2110);
FORCEPROP 2 LASTPIN (-5025 2050) $PN AY65
J 2
(-5035 2060);
DISPLAY 0.617021 (-5035 2060);
PAINT ORANGE (-5035 2060);
FORCEPROP 2 LASTPIN (-5025 1950) $PN AY67
J 2
(-5035 1960);
DISPLAY 0.617021 (-5035 1960);
PAINT ORANGE (-5035 1960);
FORCEPROP 2 LASTPIN (-5025 1900) $PN AY75
J 2
(-5035 1910);
DISPLAY 0.617021 (-5035 1910);
PAINT ORANGE (-5035 1910);
FORCEPROP 2 LASTPIN (-5025 1850) $PN AY77
J 2
(-5035 1860);
DISPLAY 0.617021 (-5035 1860);
PAINT ORANGE (-5035 1860);
FORCEPROP 2 LASTPIN (-5025 1800) $PN BA14
J 2
(-5035 1810);
DISPLAY 0.617021 (-5035 1810);
PAINT ORANGE (-5035 1810);
FORCEPROP 2 LASTPIN (-5025 1750) $PN BA16
J 2
(-5035 1760);
DISPLAY 0.617021 (-5035 1760);
PAINT ORANGE (-5035 1760);
FORCEPROP 2 LASTPIN (-5025 1700) $PN BA18
J 2
(-5035 1710);
DISPLAY 0.617021 (-5035 1710);
PAINT ORANGE (-5035 1710);
FORCEPROP 2 LASTPIN (-5025 1650) $PN BA22
J 2
(-5035 1660);
DISPLAY 0.617021 (-5035 1660);
PAINT ORANGE (-5035 1660);
FORCEPROP 2 LASTPIN (-5025 1600) $PN BA64
J 2
(-5035 1610);
DISPLAY 0.617021 (-5035 1610);
PAINT ORANGE (-5035 1610);
FORCEPROP 2 LASTPIN (-3125 1600) $PN BA66
J 0
(-3115 1610);
DISPLAY 0.617021 (-3115 1610);
PAINT ORANGE (-3115 1610);
FORCEPROP 2 LASTPIN (-3125 1550) $PN BA76
J 0
(-3115 1560);
DISPLAY 0.617021 (-3115 1560);
PAINT ORANGE (-3115 1560);
FORCEPROP 2 LASTPIN (-3125 3400) $PN CR4
J 0
(-3115 3410);
DISPLAY 0.617021 (-3115 3410);
PAINT ORANGE (-3115 3410);
FORCEPROP 2 LASTPIN (-3125 3350) $PN CM3
J 0
(-3115 3360);
DISPLAY 0.617021 (-3115 3360);
PAINT ORANGE (-3115 3360);
FORCEPROP 2 LASTPIN (-3125 3300) $PN CL4
J 0
(-3115 3310);
DISPLAY 0.617021 (-3115 3310);
PAINT ORANGE (-3115 3310);
FORCEPROP 2 LASTPIN (-3125 3250) $PN CH5
J 0
(-3115 3260);
DISPLAY 0.617021 (-3115 3260);
PAINT ORANGE (-3115 3260);
FORCEPROP 2 LASTPIN (-3125 3150) $PN CP5
J 0
(-3115 3160);
DISPLAY 0.617021 (-3115 3160);
PAINT ORANGE (-3115 3160);
FORCEPROP 2 LASTPIN (-3125 3100) $PN CN4
J 0
(-3115 3110);
DISPLAY 0.617021 (-3115 3110);
PAINT ORANGE (-3115 3110);
FORCEPROP 2 LASTPIN (-3125 3050) $PN CJ4
J 0
(-3115 3060);
DISPLAY 0.617021 (-3115 3060);
PAINT ORANGE (-3115 3060);
FORCEPROP 2 LASTPIN (-3125 3000) $PN CG4
J 0
(-3115 3010);
DISPLAY 0.617021 (-3115 3010);
PAINT ORANGE (-3115 3010);
FORCEPROP 2 LASTPIN (-5025 3400) $PN CV11
J 2
(-5035 3410);
DISPLAY 0.617021 (-5035 3410);
PAINT ORANGE (-5035 3410);
FORCEPROP 2 LASTPIN (-5025 3350) $PN CP11
J 2
(-5035 3360);
DISPLAY 0.617021 (-5035 3360);
PAINT ORANGE (-5035 3360);
FORCEPROP 2 LASTPIN (-5025 3300) $PN CN10
J 2
(-5035 3310);
DISPLAY 0.617021 (-5035 3310);
PAINT ORANGE (-5035 3310);
FORCEPROP 2 LASTPIN (-5025 3250) $PN CL10
J 2
(-5035 3260);
DISPLAY 0.617021 (-5035 3260);
PAINT ORANGE (-5035 3260);
FORCEPROP 2 LASTPIN (-5025 3150) $PN CT11
J 2
(-5035 3160);
DISPLAY 0.617021 (-5035 3160);
PAINT ORANGE (-5035 3160);
FORCEPROP 2 LASTPIN (-5025 3100) $PN CR12
J 2
(-5035 3110);
DISPLAY 0.617021 (-5035 3110);
PAINT ORANGE (-5035 3110);
FORCEPROP 2 LASTPIN (-5025 3050) $PN CM11
J 2
(-5035 3060);
DISPLAY 0.617021 (-5035 3060);
PAINT ORANGE (-5035 3060);
FORCEPROP 2 LASTPIN (-5025 3000) $PN CK9
J 2
(-5035 3010);
DISPLAY 0.617021 (-5035 3010);
PAINT ORANGE (-5035 3010);
FORCEPROP 2 LASTPIN (-5025 2200) $PN CD23
J 2
(-5035 2210);
DISPLAY 0.617021 (-5035 2210);
PAINT ORANGE (-5035 2210);
FORCEPROP 2 LASTPIN (-5025 2250) $PN CE24
J 2
(-5035 2260);
DISPLAY 0.617021 (-5035 2260);
PAINT ORANGE (-5035 2260);
FORCEPROP 2 LASTPIN (-3125 2200) $PN CC22
J 0
(-3115 2210);
DISPLAY 0.617021 (-3115 2210);
PAINT ORANGE (-3115 2210);
FORCEPROP 2 LASTPIN (-5025 2300) $PN BY21
J 2
(-5035 2310);
DISPLAY 0.617021 (-5035 2310);
PAINT ORANGE (-5035 2310);
FORCEPROP 2 LASTPIN (-5025 2350) $PN CB23
J 2
(-5035 2360);
DISPLAY 0.617021 (-5035 2360);
PAINT ORANGE (-5035 2360);
FORCEPROP 2 LASTPIN (-3125 2300) $PN CF25
J 0
(-3115 2310);
DISPLAY 0.617021 (-3115 2310);
PAINT ORANGE (-3115 2310);
FORCEPROP 2 LASTPIN (-3125 2900) $PN BW24
J 0
(-3115 2910);
DISPLAY 0.617021 (-3115 2910);
PAINT ORANGE (-3115 2910);
FORCEPROP 2 LASTPIN (-3125 2850) $PN BU24
J 0
(-3115 2860);
DISPLAY 0.617021 (-3115 2860);
PAINT ORANGE (-3115 2860);
FORCEPROP 2 LASTPIN (-5025 2900) $PN BG16
J 2
(-5035 2910);
DISPLAY 0.617021 (-5035 2910);
PAINT ORANGE (-5035 2910);
FORCEPROP 2 LASTPIN (-5025 2850) $PN BE16
J 2
(-5035 2860);
DISPLAY 0.617021 (-5035 2860);
PAINT ORANGE (-5035 2860);
FORCEPROP 2 LASTPIN (-3125 2750) $PN BK23
J 0
(-3115 2760);
DISPLAY 0.617021 (-3115 2760);
PAINT ORANGE (-3115 2760);
FORCEPROP 2 LASTPIN (-3125 2700) $PN BT19
J 0
(-3115 2710);
DISPLAY 0.617021 (-3115 2710);
PAINT ORANGE (-3115 2710);
FORCEPROP 2 LASTPIN (-3125 2650) $PN BM23
J 0
(-3115 2660);
DISPLAY 0.617021 (-3115 2660);
PAINT ORANGE (-3115 2660);
FORCEPROP 2 LASTPIN (-3125 2600) $PN BM21
J 0
(-3115 2610);
DISPLAY 0.617021 (-3115 2610);
PAINT ORANGE (-3115 2610);
FORCEPROP 2 LASTPIN (-3125 2450) $PN BH23
J 0
(-3115 2460);
DISPLAY 0.617021 (-3115 2460);
PAINT ORANGE (-3115 2460);
FORCEPROP 2 LASTPIN (-3125 2500) $PN BJ22
J 0
(-3115 2510);
DISPLAY 0.617021 (-3115 2510);
PAINT ORANGE (-3115 2510);
FORCEPROP 2 LASTPIN (-5025 2750) $PN BN24
J 2
(-5035 2760);
DISPLAY 0.617021 (-5035 2760);
PAINT ORANGE (-5035 2760);
FORCEPROP 2 LASTPIN (-5025 2700) $PN BR20
J 2
(-5035 2710);
DISPLAY 0.617021 (-5035 2710);
PAINT ORANGE (-5035 2710);
FORCEPROP 2 LASTPIN (-5025 2650) $PN BK21
J 2
(-5035 2660);
DISPLAY 0.617021 (-5035 2660);
PAINT ORANGE (-5035 2660);
FORCEPROP 2 LASTPIN (-5025 2600) $PN BP19
J 2
(-5035 2610);
DISPLAY 0.617021 (-5035 2610);
PAINT ORANGE (-5035 2610);
FORCEPROP 2 LASTPIN (-5025 2450) $PN BP23
J 2
(-5035 2460);
DISPLAY 0.617021 (-5035 2460);
PAINT ORANGE (-5035 2460);
FORCEPROP 2 LASTPIN (-5025 2500) $PN BN22
J 2
(-5035 2510);
DISPLAY 0.617021 (-5035 2510);
PAINT ORANGE (-5035 2510);
FORCEPROP 1 LAST PACK_TYPE BGA1
J 0
(-4975 3700);
PAINT SKYBLUE (-4975 3700);
DISPLAY INVISIBLE (-4975 3700);
FORCEPROP 2 LAST SEC_TYPE BGA1
J 0
(-4975 3700);
DISPLAY 1.021277 (-4975 3700);
PAINT ORANGE (-4975 3700);
DISPLAY INVISIBLE (-4975 3700);
FORCEPROP 2 LAST CDS_LIB chpset_lib
J 0
(-4075 2500);
PAINT ORANGE (-4075 2500);
DISPLAY INVISIBLE (-4075 2500);
FORCEPROP 2 LAST SEC 9
J 0
(-4975 3700);
DISPLAY 0.680851 (-4975 3700);
PAINT MONO (-4975 3700);
DISPLAY INVISIBLE (-4975 3700);
FORCEPROP 2 LAST CDS_LOCATION U2D1
J 0
(-4975 3650);
DISPLAY 0.617021 (-4975 3650);
PAINT AQUA (-4975 3650);
DISPLAY INVISIBLE (-4975 3650);
FORCEPROP 1 LAST PATH I23
J 0
(-4075 3600);
PAINT GREEN (-4075 3600);
DISPLAY INVISIBLE (-4075 3600);
FORCEADD OFFPAGE..1
(-6300 2200);
FORCEPROP 2 LAST $XR0 113 
J 0
(-6552 2200);
DISPLAY 0.638298 (-6552 2200);
PAINT MONO (-6552 2200);
FORCEPROP 2 LAST $XR1 29 
J 0
(-6642 2200);
DISPLAY 0.638298 (-6642 2200);
PAINT MONO (-6642 2200);
FORCEPROP 2 LAST CDS_LIB mstr_standard
J 0
(-6300 2200);
PAINT MONO (-6300 2200);
DISPLAY INVISIBLE (-6300 2200);
FORCEPROP 1 LAST OFFPAGE TRUE
J 0
(-5975 2075);
DISPLAY 0.872340 (-5975 2075);
PAINT GREEN (-5975 2075);
DISPLAY INVISIBLE (-5975 2075);
FORCEPROP 1 LAST COMMENT_BODY TRUE
J 0
(-6175 2100);
DISPLAY 0.872340 (-6175 2100);
PAINT GREEN (-6175 2100);
DISPLAY INVISIBLE (-6175 2100);
FORCEPROP 2 LAST PATH I26
J 0
(-6250 2275);
DISPLAY 1.021277 (-6250 2275);
PAINT ORANGE (-6250 2275);
DISPLAY INVISIBLE (-6250 2275);
FORCEADD VCC_CORE..1
(-1425 2250);
FORCEPROP 3 LASTPIN (-1425 2200) SIG_NAME PVCCMCP_CPU1\g
J 0
(-1415 2210);
DISPLAY 0.659574 (-1415 2210);
PAINT MONO (-1415 2210);
DISPLAY INVISIBLE (-1415 2210);
FORCEPROP 1 LAST HDL_POWER PVCCMCP_CPU1
J 1
(-1425 2300);
DISPLAY 0.617021 (-1425 2300);
PAINT GREEN (-1425 2300);
FORCEPROP 2 LAST CDS_LIB mstr_symbols
J 0
(-1425 2250);
PAINT ORANGE (-1425 2250);
DISPLAY INVISIBLE (-1425 2250);
FORCEPROP 1 LAST PATH I27
J 0
(-1375 2275);
DISPLAY 0.872340 (-1375 2275);
PAINT AQUA (-1375 2275);
DISPLAY INVISIBLE (-1375 2275);
FORCEADD OFFPAGE..2
(-2175 2200);
FORCEPROP 2 LAST $XR0 113 
J 0
(-1986 2200);
DISPLAY 0.638298 (-1986 2200);
PAINT MONO (-1986 2200);
FORCEPROP 2 LAST CDS_LIB mstr_standard
J 0
(-2175 2200);
PAINT ORANGE (-2175 2200);
DISPLAY INVISIBLE (-2175 2200);
FORCEPROP 1 LAST OFFPAGE TRUE
J 0
(-1850 2075);
PAINT GREEN (-1850 2075);
DISPLAY INVISIBLE (-1850 2075);
FORCEPROP 1 LAST COMMENT_BODY TRUE
J 0
(-2220 2105);
DISPLAY 1.404255 (-2220 2105);
PAINT PEACH (-2220 2105);
DISPLAY INVISIBLE (-2220 2105);
FORCEPROP 2 LAST PATH I7
J 0
(-2000 2275);
DISPLAY 1.021277 (-2000 2275);
PAINT ORANGE (-2000 2275);
DISPLAY INVISIBLE (-2000 2275);
FORCEADD OFFPAGE..1
(-6300 2300);
FORCEPROP 2 LAST $XR0 113 
J 0
(-6552 2300);
DISPLAY 0.638298 (-6552 2300);
PAINT MONO (-6552 2300);
FORCEPROP 2 LAST CDS_LIB mstr_standard
J 0
(-6300 2300);
PAINT ORANGE (-6300 2300);
DISPLAY INVISIBLE (-6300 2300);
FORCEPROP 1 LAST OFFPAGE TRUE
J 0
(-5975 2175);
DISPLAY 0.872340 (-5975 2175);
PAINT GREEN (-5975 2175);
DISPLAY INVISIBLE (-5975 2175);
FORCEPROP 1 LAST COMMENT_BODY TRUE
J 0
(-6175 2200);
DISPLAY 0.872340 (-6175 2200);
PAINT GREEN (-6175 2200);
DISPLAY INVISIBLE (-6175 2200);
FORCEPROP 2 LAST PATH I9
J 0
(-6250 2375);
DISPLAY 1.021277 (-6250 2375);
PAINT ORANGE (-6250 2375);
DISPLAY INVISIBLE (-6250 2375);
FORCEADD PRELIM..10
(-4065 2490);
PAINT GRAY (-4065 2490);
FORCEPROP 2 LAST CDS_LIB mstr_misc
J 0
(-4065 2490);
PAINT ORANGE (-4065 2490);
DISPLAY INVISIBLE (-4065 2490);
FORCEPROP 1 LAST COMMENT_BODY TRUE
J 0
(-4065 2490);
PAINT ORANGE (-4065 2490);
DISPLAY INVISIBLE (-4065 2490);
FORCEADD DESIGN_NOTE..1
(-4800 1175);
FORCEPROP 0 LAST L1 CPU SYMBOLS 1-30 ARE PRELIMINARY AND SUBJECT TO CHANGE
J 0
(-5000 1050);
DISPLAY 1.021277 (-5000 1050);
PAINT ORANGE (-5000 1050);
FORCEPROP 2 LAST CDS_LIB mstr_symbols
J 0
(-4800 1175);
PAINT ORANGE (-4800 1175);
DISPLAY INVISIBLE (-4800 1175);
FORCEPROP 1 LAST COMMENT_BODY TRUE
J 0
(-4775 1275);
DISPLAY 0.978723 (-4775 1275);
PAINT ORANGE (-4775 1275);
DISPLAY INVISIBLE (-4775 1275);
FORCEADD INTEL_CORP_BPAGE..1
(0 0);
FORCEPROP 1 LAST CDS_CON_LAST_MODIFIED Tue Dec 01 11:51:36 2015
J 0
(-1425 325);
DISPLAY 1.340426 (-1425 325);
PAINT GREEN (-1425 325);
DISPLAY INVISIBLE (-1425 325);
FORCEPROP 1 LAST CUSTOM_TXT_CDS <CURRENT_DESIGN_SHEET> OF <TOTAL_DESIGN_SHEETS>
J 0
(-500 25);
PAINT GREEN (-500 25);
FORCEPROP 1 LAST CUSTOM_TXT_CDS <CON_LAST_MODIFIED>
J 0
(-1925 350);
PAINT GREEN (-1925 350);
FORCEPROP 2 LAST CUSTOM_TXT_CDS <XR_PAGE_TITLE>
J 0
(-7890 5250);
DISPLAY 0.638298 (-7890 5250);
PAINT PINK (-7890 5250);
DISPLAY INVISIBLE (-7890 5250);
FORCEPROP 1 LAST SCH_ADDRESS3 Santa Clara, CA 95052-8119
J 0
(-3975 25);
DISPLAY 0.617021 (-3975 25);
PAINT GREEN (-3975 25);
FORCEPROP 1 LAST SCH_ADDRESS2 P.O. BOX 58119
J 0
(-3975 75);
DISPLAY 0.617021 (-3975 75);
PAINT GREEN (-3975 75);
FORCEPROP 1 LAST SCH_ADDRESS1 2200 Mission College Blvd.
J 0
(-3975 125);
DISPLAY 0.617021 (-3975 125);
PAINT GREEN (-3975 125);
FORCEPROP 1 LAST SCH_TITLE SKYLAKE - SKT1 - 9 OF 21
J 0
(-7950 50);
DISPLAY 1.212766 (-7950 50);
PAINT GREEN (-7950 50);
FORCEPROP 1 LAST SCH_NUMBER H4694802
J 0
(-1300 150);
DISPLAY 1.212766 (-1300 150);
PAINT YELLOW (-1300 150);
FORCEPROP 1 LAST SCH_DEPT BESD
J 1
(-4450 100);
DISPLAY 1.212766 (-4450 100);
PAINT YELLOW (-4450 100);
FORCEPROP 1 LAST SCH_REV 2.420
J 0
(-250 150);
DISPLAY 0.978723 (-250 150);
PAINT YELLOW (-250 150);
FORCEPROP 2 LAST CDS_LIB mstr_symbols
J 0
(0 0);
PAINT ORANGE (0 0);
DISPLAY INVISIBLE (0 0);
FORCEPROP 2 LAST PAGE_BORDER TRUE
J 0
(-7890 5250);
DISPLAY 0.851064 (-7890 5250);
PAINT PINK (-7890 5250);
DISPLAY INVISIBLE (-7890 5250);
FORCEPROP 1 LAST COMMENT_BODY TRUE
J 0
(12 12);
DISPLAY 0.638298 (12 12);
PAINT GREEN (12 12);
DISPLAY INVISIBLE (12 12);
FORCEPROP 2 LAST CDS_XR_PAGE_TITLE CR-63 : @BASEBOARD_FAB2_LIB.BASEBOARD_FAB2(SCH_1):PAGE63
J 0
(-7890 5250);
DISPLAY 0.638298 (-7890 5250);
PAINT PINK (-7890 5250);
DISPLAY INVISIBLE (-7890 5250);
WIRE 16 -1 (-3125 1950)(-2950 1950);
WIRE 16 -1 (-2950 1950)(-2950 2050);
WIRE 16 -1 (-3125 2050)(-2950 2050);
WIRE 16 -1 (-2950 2050)(-2950 2100);
WIRE 16 -1 (-3125 2100)(-2950 2100);
WIRE 16 -1 (-2950 2100)(-1425 2100);
WIRE 16 -1 (-1425 1800)(-1425 2100);
WIRE 16 -1 (-1425 2100)(-1425 2200);
WIRE 16 -1 (-2975 1800)(-1425 1800);
WIRE 16 -1 (-2975 1750)(-2975 1800);
WIRE 16 -1 (-3125 1800)(-2975 1800);
WIRE 16 -1 (-3125 1750)(-2975 1750);
WIRE 16 -1 (-5025 2750)(-6275 2750);
FORCEPROP 2 LAST SIG_NAME TP_RST_CPU1_CD_HFI0_N
J 0
(-6225 2760);
DISPLAY 0.617021 (-6225 2760);
PAINT ORANGE (-6225 2760);
FORCEPROP 2 LASTPROP $XRERR UNIQUE?
J 0
(-6515 2750);
DISPLAY 0.638298 (-6515 2750);
PAINT MONO (-6515 2750);
DISPLAY INVISIBLE (-6515 2750);
WIRE 16 -1 (-5025 2700)(-6275 2700);
FORCEPROP 2 LAST SIG_NAME TP_FM_CPU1_CD_HFI0_MODPRST_N
J 0
(-6225 2710);
DISPLAY 0.617021 (-6225 2710);
PAINT ORANGE (-6225 2710);
FORCEPROP 2 LASTPROP $XRERR UNIQUE?
J 0
(-6515 2700);
DISPLAY 0.638298 (-6515 2700);
PAINT MONO (-6515 2700);
DISPLAY INVISIBLE (-6515 2700);
WIRE 16 -1 (-6275 2650)(-5025 2650);
FORCEPROP 2 LAST SIG_NAME TP_LED_CPU1_CD_HFI0_N
J 0
(-6225 2660);
DISPLAY 0.617021 (-6225 2660);
PAINT ORANGE (-6225 2660);
FORCEPROP 2 LASTPROP $XRERR UNIQUE?
J 0
(-6515 2650);
DISPLAY 0.638298 (-6515 2650);
PAINT MONO (-6515 2650);
DISPLAY INVISIBLE (-6515 2650);
WIRE 16 -1 (-6275 2600)(-5025 2600);
FORCEPROP 2 LAST SIG_NAME TP_IRQ_CPU1_CD_HFI0_N
J 0
(-6225 2610);
DISPLAY 0.617021 (-6225 2610);
PAINT ORANGE (-6225 2610);
FORCEPROP 2 LASTPROP $XRERR UNIQUE?
J 0
(-6515 2600);
DISPLAY 0.638298 (-6515 2600);
PAINT MONO (-6515 2600);
DISPLAY INVISIBLE (-6515 2600);
WIRE 16 -1 (-5025 2450)(-6275 2450);
FORCEPROP 2 LAST SIG_NAME TP_SMB_CPU1_CD_HFI0_I2CDAT
J 0
(-6225 2460);
DISPLAY 0.617021 (-6225 2460);
PAINT ORANGE (-6225 2460);
FORCEPROP 2 LASTPROP $XRERR UNIQUE?
J 0
(-6515 2450);
DISPLAY 0.638298 (-6515 2450);
PAINT MONO (-6515 2450);
DISPLAY INVISIBLE (-6515 2450);
WIRE 16 -1 (-6275 2500)(-5025 2500);
FORCEPROP 2 LAST SIG_NAME TP_SMB_CPU1_CD_HFI0_I2CCLK
J 0
(-6225 2510);
DISPLAY 0.617021 (-6225 2510);
PAINT ORANGE (-6225 2510);
FORCEPROP 2 LASTPROP $XRERR UNIQUE?
J 0
(-6515 2500);
DISPLAY 0.638298 (-6515 2500);
PAINT MONO (-6515 2500);
DISPLAY INVISIBLE (-6515 2500);
WIRE 16 -1 (-5025 2250)(-6250 2250);
FORCEPROP 2 LAST SIG_NAME JTAG_MCP_TMS
J 0
(-6210 2260);
DISPLAY 0.617021 (-6210 2260);
PAINT ORANGE (-6210 2260);
WIRE 16 -1 (-6250 2350)(-5025 2350);
FORCEPROP 2 LAST SIG_NAME JTAG_MCP_TCK
J 0
(-6210 2360);
DISPLAY 0.617021 (-6210 2360);
PAINT ORANGE (-6210 2360);
WIRE 16 -1 (-5025 2900)(-6250 2900);
FORCEPROP 2 LAST SIG_NAME CLK_156M_OSC_CPU1_HFI_DP
J 0
(-6160 2910);
DISPLAY 0.617021 (-6160 2910);
PAINT ORANGE (-6160 2910);
WIRE 16 -1 (-6250 2850)(-5025 2850);
FORCEPROP 2 LAST SIG_NAME CLK_156M_OSC_CPU1_HFI_DN
J 0
(-6160 2860);
DISPLAY 0.617021 (-6160 2860);
PAINT ORANGE (-6160 2860);
WIRE 16 -1 (-5025 2200)(-6250 2200);
FORCEPROP 2 LAST SIG_NAME JTAG_MCP_TRST_N
J 0
(-6210 2210);
DISPLAY 0.617021 (-6210 2210);
PAINT ORANGE (-6210 2210);
WIRE 16 -1 (-5025 2300)(-6250 2300);
FORCEPROP 2 LAST SIG_NAME JTAG_MCP_CPU1_TDI
J 0
(-6210 2310);
DISPLAY 0.617021 (-6210 2310);
PAINT ORANGE (-6210 2310);
WIRE 16 -1 (-5025 1600)(-5825 1600);
FORCEPROP 2 LAST SIG_NAME TP_CPU1_RSVD_174
J 0
(-5800 1610);
DISPLAY 0.617021 (-5800 1610);
PAINT ORANGE (-5800 1610);
FORCEPROP 2 LASTPROP $XRERR UNIQUE?
J 0
(-6065 1600);
DISPLAY 0.638298 (-6065 1600);
PAINT MONO (-6065 1600);
DISPLAY INVISIBLE (-6065 1600);
WIRE 16 -1 (-5025 1650)(-5825 1650);
FORCEPROP 2 LAST SIG_NAME TP_CPU1_RSVD_175
J 0
(-5800 1660);
DISPLAY 0.617021 (-5800 1660);
PAINT ORANGE (-5800 1660);
FORCEPROP 2 LASTPROP $XRERR UNIQUE?
J 0
(-6065 1650);
DISPLAY 0.638298 (-6065 1650);
PAINT MONO (-6065 1650);
DISPLAY INVISIBLE (-6065 1650);
WIRE 16 -1 (-5025 1700)(-5825 1700);
FORCEPROP 2 LAST SIG_NAME TP_CPU1_RSVD_176
J 0
(-5800 1710);
DISPLAY 0.617021 (-5800 1710);
PAINT ORANGE (-5800 1710);
FORCEPROP 2 LASTPROP $XRERR UNIQUE?
J 0
(-6065 1700);
DISPLAY 0.638298 (-6065 1700);
PAINT MONO (-6065 1700);
DISPLAY INVISIBLE (-6065 1700);
WIRE 16 -1 (-5025 1750)(-5825 1750);
FORCEPROP 2 LAST SIG_NAME TP_CPU1_RSVD_177
J 0
(-5800 1760);
DISPLAY 0.617021 (-5800 1760);
PAINT ORANGE (-5800 1760);
FORCEPROP 2 LASTPROP $XRERR UNIQUE?
J 0
(-6065 1750);
DISPLAY 0.638298 (-6065 1750);
PAINT MONO (-6065 1750);
DISPLAY INVISIBLE (-6065 1750);
WIRE 16 -1 (-5025 1800)(-5825 1800);
FORCEPROP 2 LAST SIG_NAME TP_CPU1_RSVD_178
J 0
(-5800 1810);
DISPLAY 0.617021 (-5800 1810);
PAINT ORANGE (-5800 1810);
FORCEPROP 2 LASTPROP $XRERR UNIQUE?
J 0
(-6065 1800);
DISPLAY 0.638298 (-6065 1800);
PAINT MONO (-6065 1800);
DISPLAY INVISIBLE (-6065 1800);
WIRE 16 -1 (-5025 1850)(-5825 1850);
FORCEPROP 2 LAST SIG_NAME TP_CPU1_RSVD_179
J 0
(-5800 1860);
DISPLAY 0.617021 (-5800 1860);
PAINT ORANGE (-5800 1860);
FORCEPROP 2 LASTPROP $XRERR UNIQUE?
J 0
(-6065 1850);
DISPLAY 0.638298 (-6065 1850);
PAINT MONO (-6065 1850);
DISPLAY INVISIBLE (-6065 1850);
WIRE 16 -1 (-5025 1900)(-5825 1900);
FORCEPROP 2 LAST SIG_NAME TP_CPU1_RSVD_180
J 0
(-5800 1910);
DISPLAY 0.617021 (-5800 1910);
PAINT ORANGE (-5800 1910);
FORCEPROP 2 LASTPROP $XRERR UNIQUE?
J 0
(-6065 1900);
DISPLAY 0.638298 (-6065 1900);
PAINT MONO (-6065 1900);
DISPLAY INVISIBLE (-6065 1900);
WIRE 16 -1 (-5025 1950)(-5825 1950);
FORCEPROP 2 LAST SIG_NAME TP_CPU1_RSVD_181
J 0
(-5800 1960);
DISPLAY 0.617021 (-5800 1960);
PAINT ORANGE (-5800 1960);
FORCEPROP 2 LASTPROP $XRERR UNIQUE?
J 0
(-6065 1950);
DISPLAY 0.638298 (-6065 1950);
PAINT MONO (-6065 1950);
DISPLAY INVISIBLE (-6065 1950);
WIRE 16 -1 (-5675 3250)(-5025 3250);
FORCEPROP 0 LAST SIG_NAME TP_CPU1_DMI_RX_DP0
J 0
(-5660 3260);
DISPLAY 0.617021 (-5660 3260);
PAINT ORANGE (-5660 3260);
FORCEPROP 2 LASTPROP $XRERR UNIQUE?
J 0
(-5915 3250);
DISPLAY 0.638298 (-5915 3250);
PAINT MONO (-5915 3250);
DISPLAY INVISIBLE (-5915 3250);
WIRE 16 -1 (-5675 3300)(-5025 3300);
FORCEPROP 0 LAST SIG_NAME TP_CPU1_DMI_RX_DP1
J 0
(-5660 3310);
DISPLAY 0.617021 (-5660 3310);
PAINT ORANGE (-5660 3310);
FORCEPROP 2 LASTPROP $XRERR UNIQUE?
J 0
(-5915 3300);
DISPLAY 0.638298 (-5915 3300);
PAINT MONO (-5915 3300);
DISPLAY INVISIBLE (-5915 3300);
WIRE 16 -1 (-5675 3350)(-5025 3350);
FORCEPROP 0 LAST SIG_NAME TP_CPU1_DMI_RX_DP2
J 0
(-5660 3360);
DISPLAY 0.617021 (-5660 3360);
PAINT ORANGE (-5660 3360);
FORCEPROP 2 LASTPROP $XRERR UNIQUE?
J 0
(-5915 3350);
DISPLAY 0.638298 (-5915 3350);
PAINT MONO (-5915 3350);
DISPLAY INVISIBLE (-5915 3350);
WIRE 16 -1 (-5675 3400)(-5025 3400);
FORCEPROP 0 LAST SIG_NAME TP_CPU1_DMI_RX_DP3
J 0
(-5660 3410);
DISPLAY 0.617021 (-5660 3410);
PAINT ORANGE (-5660 3410);
FORCEPROP 2 LASTPROP $XRERR UNIQUE?
J 0
(-5915 3400);
DISPLAY 0.638298 (-5915 3400);
PAINT MONO (-5915 3400);
DISPLAY INVISIBLE (-5915 3400);
WIRE 16 -1 (-5675 3000)(-5025 3000);
FORCEPROP 0 LAST SIG_NAME TP_CPU1_DMI_RX_DN0
J 0
(-5685 3010);
DISPLAY 0.617021 (-5685 3010);
PAINT ORANGE (-5685 3010);
FORCEPROP 2 LASTPROP $XRERR UNIQUE?
J 0
(-5915 3000);
DISPLAY 0.638298 (-5915 3000);
PAINT MONO (-5915 3000);
DISPLAY INVISIBLE (-5915 3000);
WIRE 16 -1 (-5675 3050)(-5025 3050);
FORCEPROP 0 LAST SIG_NAME TP_CPU1_DMI_RX_DN1
J 0
(-5685 3060);
DISPLAY 0.617021 (-5685 3060);
PAINT ORANGE (-5685 3060);
FORCEPROP 2 LASTPROP $XRERR UNIQUE?
J 0
(-5915 3050);
DISPLAY 0.638298 (-5915 3050);
PAINT MONO (-5915 3050);
DISPLAY INVISIBLE (-5915 3050);
WIRE 16 -1 (-5025 3100)(-5675 3100);
FORCEPROP 0 LAST SIG_NAME TP_CPU1_DMI_RX_DN2
J 0
(-5685 3110);
DISPLAY 0.617021 (-5685 3110);
PAINT ORANGE (-5685 3110);
FORCEPROP 2 LASTPROP $XRERR UNIQUE?
J 0
(-5915 3100);
DISPLAY 0.638298 (-5915 3100);
PAINT MONO (-5915 3100);
DISPLAY INVISIBLE (-5915 3100);
WIRE 16 -1 (-5675 3150)(-5025 3150);
FORCEPROP 0 LAST SIG_NAME TP_CPU1_DMI_RX_DN3
J 0
(-5685 3160);
DISPLAY 0.617021 (-5685 3160);
PAINT ORANGE (-5685 3160);
FORCEPROP 2 LASTPROP $XRERR UNIQUE?
J 0
(-5915 3150);
DISPLAY 0.638298 (-5915 3150);
PAINT MONO (-5915 3150);
DISPLAY INVISIBLE (-5915 3150);
WIRE 16 -1 (-5025 2050)(-5825 2050);
FORCEPROP 2 LAST SIG_NAME TP_CPU1_RSVD_182
J 0
(-5800 2060);
DISPLAY 0.617021 (-5800 2060);
PAINT ORANGE (-5800 2060);
FORCEPROP 2 LASTPROP $XRERR UNIQUE?
J 0
(-6065 2050);
DISPLAY 0.638298 (-6065 2050);
PAINT MONO (-6065 2050);
DISPLAY INVISIBLE (-6065 2050);
WIRE 16 -1 (-5025 2100)(-5825 2100);
FORCEPROP 2 LAST SIG_NAME TP_CPU1_RSVD_183
J 0
(-5800 2110);
DISPLAY 0.617021 (-5800 2110);
PAINT ORANGE (-5800 2110);
FORCEPROP 2 LASTPROP $XRERR UNIQUE?
J 0
(-6065 2100);
DISPLAY 0.638298 (-6065 2100);
PAINT MONO (-6065 2100);
DISPLAY INVISIBLE (-6065 2100);
WIRE 16 -1 (-2325 1550)(-3125 1550);
FORCEPROP 2 LAST SIG_NAME TP_CPU1_RSVD_172
J 0
(-2850 1560);
DISPLAY 0.617021 (-2850 1560);
PAINT ORANGE (-2850 1560);
FORCEPROP 2 LASTPROP $XRERR UNIQUE?
J 0
(-2295 1550);
DISPLAY 0.638298 (-2295 1550);
PAINT MONO (-2295 1550);
DISPLAY INVISIBLE (-2295 1550);
WIRE 16 -1 (-2325 1600)(-3125 1600);
FORCEPROP 2 LAST SIG_NAME TP_CPU1_RSVD_173
J 0
(-2850 1610);
DISPLAY 0.617021 (-2850 1610);
PAINT ORANGE (-2850 1610);
FORCEPROP 2 LASTPROP $XRERR UNIQUE?
J 0
(-2295 1600);
DISPLAY 0.638298 (-2295 1600);
PAINT MONO (-2295 1600);
DISPLAY INVISIBLE (-2295 1600);
WIRE 16 -1 (-2325 1650)(-3125 1650);
FORCEPROP 2 LAST SIG_NAME TP_CPU1_RSVD_184
J 0
(-2850 1660);
DISPLAY 0.617021 (-2850 1660);
PAINT ORANGE (-2850 1660);
FORCEPROP 2 LASTPROP $XRERR UNIQUE?
J 0
(-2295 1650);
DISPLAY 0.638298 (-2295 1650);
PAINT MONO (-2295 1650);
DISPLAY INVISIBLE (-2295 1650);
WIRE 16 -1 (-2325 1700)(-3125 1700);
FORCEPROP 2 LAST SIG_NAME TP_CPU1_RSVD_186
J 0
(-2850 1710);
DISPLAY 0.617021 (-2850 1710);
PAINT ORANGE (-2850 1710);
FORCEPROP 2 LASTPROP $XRERR UNIQUE?
J 0
(-2295 1700);
DISPLAY 0.638298 (-2295 1700);
PAINT MONO (-2295 1700);
DISPLAY INVISIBLE (-2295 1700);
WIRE 16 -1 (-2325 1900)(-3125 1900);
FORCEPROP 2 LAST SIG_NAME TP_CPU1_RSVD_190
J 0
(-2850 1910);
DISPLAY 0.617021 (-2850 1910);
PAINT ORANGE (-2850 1910);
FORCEPROP 2 LASTPROP $XRERR UNIQUE?
J 0
(-2295 1900);
DISPLAY 0.638298 (-2295 1900);
PAINT MONO (-2295 1900);
DISPLAY INVISIBLE (-2295 1900);
WIRE 16 -1 (-2325 1850)(-3125 1850);
FORCEPROP 2 LAST SIG_NAME TP_CPU1_RSVD_189
J 0
(-2850 1860);
DISPLAY 0.617021 (-2850 1860);
PAINT ORANGE (-2850 1860);
FORCEPROP 2 LASTPROP $XRERR UNIQUE?
J 0
(-2295 1850);
DISPLAY 0.638298 (-2295 1850);
PAINT MONO (-2295 1850);
DISPLAY INVISIBLE (-2295 1850);
WIRE 16 -1 (-2350 3250)(-3125 3250);
FORCEPROP 0 LAST SIG_NAME TP_CPU1_DMI_TX_DP0
J 0
(-2960 3260);
DISPLAY 0.617021 (-2960 3260);
PAINT ORANGE (-2960 3260);
FORCEPROP 2 LASTPROP $XRERR UNIQUE?
J 0
(-2320 3250);
DISPLAY 0.638298 (-2320 3250);
PAINT MONO (-2320 3250);
DISPLAY INVISIBLE (-2320 3250);
WIRE 16 -1 (-3125 3300)(-2350 3300);
FORCEPROP 0 LAST SIG_NAME TP_CPU1_DMI_TX_DP1
J 0
(-2960 3310);
DISPLAY 0.617021 (-2960 3310);
PAINT ORANGE (-2960 3310);
FORCEPROP 2 LASTPROP $XRERR UNIQUE?
J 0
(-2320 3300);
DISPLAY 0.638298 (-2320 3300);
PAINT MONO (-2320 3300);
DISPLAY INVISIBLE (-2320 3300);
WIRE 16 -1 (-3125 3350)(-2350 3350);
FORCEPROP 0 LAST SIG_NAME TP_CPU1_DMI_TX_DP2
J 0
(-2960 3360);
DISPLAY 0.617021 (-2960 3360);
PAINT ORANGE (-2960 3360);
FORCEPROP 2 LASTPROP $XRERR UNIQUE?
J 0
(-2320 3350);
DISPLAY 0.638298 (-2320 3350);
PAINT MONO (-2320 3350);
DISPLAY INVISIBLE (-2320 3350);
WIRE 16 -1 (-3125 3400)(-2350 3400);
FORCEPROP 0 LAST SIG_NAME TP_CPU1_DMI_TX_DP3
J 0
(-2960 3410);
DISPLAY 0.617021 (-2960 3410);
PAINT ORANGE (-2960 3410);
FORCEPROP 2 LASTPROP $XRERR UNIQUE?
J 0
(-2320 3400);
DISPLAY 0.638298 (-2320 3400);
PAINT MONO (-2320 3400);
DISPLAY INVISIBLE (-2320 3400);
WIRE 16 -1 (-2100 3000)(-3125 3000);
FORCEPROP 0 LAST SIG_NAME TP_CPU1_DMI_TX_DN0
J 0
(-2935 3010);
DISPLAY 0.617021 (-2935 3010);
PAINT ORANGE (-2935 3010);
FORCEPROP 2 LASTPROP $XRERR UNIQUE?
J 0
(-2070 3000);
DISPLAY 0.638298 (-2070 3000);
PAINT MONO (-2070 3000);
DISPLAY INVISIBLE (-2070 3000);
WIRE 16 -1 (-3125 3050)(-2100 3050);
FORCEPROP 0 LAST SIG_NAME TP_CPU1_DMI_TX_DN1
J 0
(-2935 3060);
DISPLAY 0.617021 (-2935 3060);
PAINT ORANGE (-2935 3060);
FORCEPROP 2 LASTPROP $XRERR UNIQUE?
J 0
(-2070 3050);
DISPLAY 0.638298 (-2070 3050);
PAINT MONO (-2070 3050);
DISPLAY INVISIBLE (-2070 3050);
WIRE 16 -1 (-2100 3100)(-3125 3100);
FORCEPROP 0 LAST SIG_NAME TP_CPU1_DMI_TX_DN2
J 0
(-2935 3110);
DISPLAY 0.617021 (-2935 3110);
PAINT ORANGE (-2935 3110);
FORCEPROP 2 LASTPROP $XRERR UNIQUE?
J 0
(-2070 3100);
DISPLAY 0.638298 (-2070 3100);
PAINT MONO (-2070 3100);
DISPLAY INVISIBLE (-2070 3100);
WIRE 16 -1 (-3125 3150)(-2100 3150);
FORCEPROP 0 LAST SIG_NAME TP_CPU1_DMI_TX_DN3
J 0
(-2935 3160);
DISPLAY 0.617021 (-2935 3160);
PAINT ORANGE (-2935 3160);
FORCEPROP 2 LASTPROP $XRERR UNIQUE?
J 0
(-2070 3150);
DISPLAY 0.638298 (-2070 3150);
PAINT MONO (-2070 3150);
DISPLAY INVISIBLE (-2070 3150);
WIRE 16 -1 (-2200 2900)(-3125 2900);
FORCEPROP 2 LAST SIG_NAME CLK_100M_CPU1_PE_REFCLK_DP
J 0
(-2950 2910);
DISPLAY 0.617021 (-2950 2910);
PAINT ORANGE (-2950 2910);
WIRE 16 -1 (-2200 2850)(-3125 2850);
FORCEPROP 0 LAST SIG_NAME CLK_100M_CPU1_PE_REFCLK_DN
J 0
(-2950 2860);
DISPLAY 0.617021 (-2950 2860);
PAINT ORANGE (-2950 2860);
WIRE 16 -1 (-2225 2300)(-3125 2300);
FORCEPROP 2 LAST SIG_NAME RST_CD_CPU1_POR_N
J 0
(-2850 2310);
DISPLAY 0.617021 (-2850 2310);
PAINT ORANGE (-2850 2310);
WIRE 16 -1 (-2225 2200)(-3125 2200);
FORCEPROP 2 LAST SIG_NAME JTAG_MCP_CPU1_TDO
J 0
(-2860 2210);
DISPLAY 0.617021 (-2860 2210);
PAINT ORANGE (-2860 2210);
WIRE 16 -1 (-1775 2750)(-3125 2750);
FORCEPROP 2 LAST SIG_NAME TP_CD_HFI1_CPU1_RESET_N
J 0
(-2975 2760);
DISPLAY 0.617021 (-2975 2760);
PAINT ORANGE (-2975 2760);
FORCEPROP 2 LASTPROP $XRERR UNIQUE?
J 0
(-1745 2750);
DISPLAY 0.638298 (-1745 2750);
PAINT MONO (-1745 2750);
DISPLAY INVISIBLE (-1745 2750);
WIRE 16 -1 (-1775 2700)(-3125 2700);
FORCEPROP 2 LAST SIG_NAME TP_CD_HFI1_CPU1_MODPRST_N
J 0
(-2975 2710);
DISPLAY 0.617021 (-2975 2710);
PAINT ORANGE (-2975 2710);
FORCEPROP 2 LASTPROP $XRERR UNIQUE?
J 0
(-1745 2700);
DISPLAY 0.638298 (-1745 2700);
PAINT MONO (-1745 2700);
DISPLAY INVISIBLE (-1745 2700);
WIRE 16 -1 (-3125 2650)(-1775 2650);
FORCEPROP 2 LAST SIG_NAME TP_CD_HFI1_CPU1_LED_N
J 0
(-2975 2660);
DISPLAY 0.617021 (-2975 2660);
PAINT ORANGE (-2975 2660);
FORCEPROP 2 LASTPROP $XRERR UNIQUE?
J 0
(-1745 2650);
DISPLAY 0.638298 (-1745 2650);
PAINT MONO (-1745 2650);
DISPLAY INVISIBLE (-1745 2650);
WIRE 16 -1 (-1775 2600)(-3125 2600);
FORCEPROP 2 LAST SIG_NAME TP_CD_HFI1_CPU1_INT_N
J 0
(-2975 2610);
DISPLAY 0.617021 (-2975 2610);
PAINT ORANGE (-2975 2610);
FORCEPROP 2 LASTPROP $XRERR UNIQUE?
J 0
(-1745 2600);
DISPLAY 0.638298 (-1745 2600);
PAINT MONO (-1745 2600);
DISPLAY INVISIBLE (-1745 2600);
WIRE 16 -1 (-1900 2450)(-3125 2450);
FORCEPROP 2 LAST SIG_NAME TP_CD_HFI1_CPU1_I2CDAT
J 0
(-2975 2460);
DISPLAY 0.617021 (-2975 2460);
PAINT ORANGE (-2975 2460);
FORCEPROP 2 LASTPROP $XRERR UNIQUE?
J 0
(-1870 2450);
DISPLAY 0.638298 (-1870 2450);
PAINT MONO (-1870 2450);
DISPLAY INVISIBLE (-1870 2450);
WIRE 16 -1 (-1900 2500)(-3125 2500);
FORCEPROP 2 LAST SIG_NAME TP_CD_HFI1_CPU1_I2CLK
J 0
(-2975 2510);
DISPLAY 0.617021 (-2975 2510);
PAINT ORANGE (-2975 2510);
FORCEPROP 2 LASTPROP $XRERR UNIQUE?
J 0
(-1870 2500);
DISPLAY 0.638298 (-1870 2500);
PAINT MONO (-1870 2500);
DISPLAY INVISIBLE (-1870 2500);
DOT 1 (-2950 2100);
DOT 1 (-1425 2100);
DOT 1 (-2975 1800);
DOT 1 (-2950 2050);
FORCENOTE
ROOM=CPU1
(-7975 375) 0;
DISPLAY LEFT (-7975 375);
DISPLAY 1.723404 (-7975 375);
PAINT PURPLE (-7975 375);
FORCENOTE
BOM_COST=PROC_SOCKET
(-7975 250) 0;
DISPLAY LEFT (-7975 250);
DISPLAY 1.723404 (-7975 250);
PAINT PURPLE (-7975 250);
QUIT
